# T6G (Grand Teton) — schematic netlist excerpt (pin names and nets, part order shuffled) for the footprints in the layout excerpt that follows; sources: Cadence DE-HDL packaged netlist, KiCad conversion of 04192023_DAF0TMB3IC0_F0TG_MB_C_brd_V02_OCP.brd

R1299  Q_RES  0 5% CHIP  pkg 0402LF  page 159 : A = I3C_SPD_DDRGL_CPU0_SCL ; B = I3C_SPD_DDRGL_CPU0_LVC1_SCL
R1556  Q_RES  33 5% CHIP  pkg 0402LF  page 81 : A = CLK_ESPI_CPU0_R1_CLK1 ; B = CLK_ESPI_CPU0_CLK1

(kicad_pcb
	(version 20260206)
	(generator "pcbnew")
	(generator_version "10.0")
	(general
		(thickness 1.6)
		(legacy_teardrops no)
	)
	(paper "A4")
	(title_block
		(title "04192023_DAF0TMB3IC0_F0TG_MB_C_brd_V02_OCP.brd")
		(comment 1 "Grand Teton / footprints 2478-2479 of 8354")
	)
	(layers
		(0 "F.Cu" signal "TOP")
		(4 "In1.Cu" signal "GND")
		(6 "In2.Cu" signal "IN1")
		(8 "In3.Cu" signal "GND1")
		(10 "In4.Cu" signal "IN2")
		(12 "In5.Cu" signal "GND2")
		(14 "In6.Cu" signal "IN3")
		(16 "In7.Cu" signal "GND3")
		(18 "In8.Cu" signal "VCC")
		(20 "In9.Cu" signal "VCC1")
		(22 "In10.Cu" signal "GND4")
		(24 "In11.Cu" signal "IN4")
		(26 "In12.Cu" signal "GND5")
		(28 "In13.Cu" signal "IN5")
		(30 "In14.Cu" signal "GND6")
		(32 "In15.Cu" signal "IN6")
		(34 "In16.Cu" signal "GND7")
		(2 "B.Cu" signal "BOTTOM")
		(9 "F.Adhes" user "F.Adhesive")
		(11 "B.Adhes" user "B.Adhesive")
		(13 "F.Paste" user "Package Geometry/Pastemask Top")
		(15 "B.Paste" user "Package Geometry/Pastemask Bottom")
		(5 "F.SilkS" user "Ref Des/Silkscreen Top")
		(7 "B.SilkS" user "Ref Des/Silkscreen Bottom")
		(1 "F.Mask" user "Board Geometry/Soldermask Top")
		(3 "B.Mask" user "Board Geometry/Soldermask Bottom")
		(17 "Dwgs.User" user "User.Drawings")
		(19 "Cmts.User" user "User.Comments")
		(21 "Eco1.User" user "User.Eco1")
		(23 "Eco2.User" user "User.Eco2")
		(25 "Edge.Cuts" user "Board Geometry/Outline")
		(27 "Margin" user)
		(31 "F.CrtYd" user "Package Geometry/Place Bound Top")
		(29 "B.CrtYd" user "Package Geometry/Place Bound Bottom")
		(35 "F.Fab" user "Ref Des/Assembly Top")
		(33 "B.Fab" user "Ref Des/Assembly Bottom")
	)
	(footprint ""
		(layer "F.Cu")
		(at 196.342 -137.632948 90)
		(property "Reference" "R1556"
			(at 0 0 90)
			(layer "F.SilkS")
			(hide yes)
			(effects
				(font
					(size 1.27 1.27)
				)
			)
		)
		(property "Value" ""
			(at 0 0 90)
			(layer "F.Fab")
			(effects
				(font
					(size 1.27 1.27)
				)
			)
		)
		(duplicate_pad_numbers_are_jumpers no)
		(fp_line
			(start 0.7874 -0.4064)
			(end 0.7874 0.4064)
			(stroke
				(width 0.1524)
				(type default)
			)
			(layer "F.SilkS")
		)
		(fp_line
			(start -0.7874 -0.4064)
			(end 0.7874 -0.4064)
			(stroke
				(width 0.1524)
				(type default)
			)
			(layer "F.SilkS")
		)
		(fp_line
			(start 0.7874 0.4064)
			(end -0.7874 0.4064)
			(stroke
				(width 0.1524)
				(type default)
			)
			(layer "F.SilkS")
		)
		(fp_line
			(start -0.7874 0.4064)
			(end -0.7874 -0.4064)
			(stroke
				(width 0.1524)
				(type default)
			)
			(layer "F.SilkS")
		)
		(fp_line
			(start -0.12065 -0.305054)
			(end -0.12065 -0.2794)
			(stroke
				(width 0.1)
				(type default)
			)
			(layer "F.Fab")
		)
		(fp_line
			(start -0.67945 -0.305054)
			(end -0.12065 -0.305054)
			(stroke
				(width 0.1)
				(type default)
			)
			(layer "F.Fab")
		)
		(fp_line
			(start 0.67945 -0.3048)
			(end 0.67945 0.3048)
			(stroke
				(width 0.1)
				(type default)
			)
			(layer "F.Fab")
		)
		(fp_line
			(start 0.12065 -0.3048)
			(end 0.67945 -0.3048)
			(stroke
				(width 0.1)
				(type default)
			)
			(layer "F.Fab")
		)
		(fp_line
			(start 0.12065 -0.2794)
			(end 0.12065 -0.3048)
			(stroke
				(width 0.1)
				(type default)
			)
			(layer "F.Fab")
		)
		(fp_line
			(start -0.12065 -0.2794)
			(end 0.12065 -0.2794)
			(stroke
				(width 0.1)
				(type default)
			)
			(layer "F.Fab")
		)
		(fp_line
			(start 0.120396 0.2794)
			(end -0.12065 0.2794)
			(stroke
				(width 0.1)
				(type default)
			)
			(layer "F.Fab")
		)
		(fp_line
			(start -0.12065 0.2794)
			(end -0.12065 0.3048)
			(stroke
				(width 0.1)
				(type default)
			)
			(layer "F.Fab")
		)
		(fp_line
			(start 0.67945 0.3048)
			(end 0.120396 0.3048)
			(stroke
				(width 0.1)
				(type default)
			)
			(layer "F.Fab")
		)
		(fp_line
			(start 0.120396 0.3048)
			(end 0.120396 0.2794)
			(stroke
				(width 0.1)
				(type default)
			)
			(layer "F.Fab")
		)
		(fp_line
			(start -0.12065 0.3048)
			(end -0.67945 0.3048)
			(stroke
				(width 0.1)
				(type default)
			)
			(layer "F.Fab")
		)
		(fp_line
			(start -0.67945 0.3048)
			(end -0.67945 -0.305054)
			(stroke
				(width 0.1)
				(type default)
			)
			(layer "F.Fab")
		)
		(pad "1" smd circle
			(at -0.40005 0 90)
			(size 0 0)
			(layers "F.Cu" "F.Mask" "F.Paste")
			(net "CLK_ESPI_CPU0_R1_CLK1")
		)
		(pad "2" smd circle
			(at 0.40005 0 90)
			(size 0 0)
			(layers "F.Cu" "F.Mask" "F.Paste")
			(net "CLK_ESPI_CPU0_CLK1")
		)
	)
	(footprint ""
		(layer "F.Cu")
		(at 435.102 -166.751 90)
		(property "Reference" "R1299"
			(at 0 0 90)
			(layer "F.SilkS")
			(hide yes)
			(effects
				(font
					(size 1.27 1.27)
				)
			)
		)
		(property "Value" ""
			(at 0 0 90)
			(layer "F.Fab")
			(effects
				(font
					(size 1.27 1.27)
				)
			)
		)
		(duplicate_pad_numbers_are_jumpers no)
		(fp_line
			(start 0.7874 -0.4064)
			(end 0.7874 0.4064)
			(stroke
				(width 0.1524)
				(type default)
			)
			(layer "F.SilkS")
		)
		(fp_line
			(start -0.7874 -0.4064)
			(end 0.7874 -0.4064)
			(stroke
				(width 0.1524)
				(type default)
			)
			(layer "F.SilkS")
		)
		(fp_line
			(start 0.7874 0.4064)
			(end -0.7874 0.4064)
			(stroke
				(width 0.1524)
				(type default)
			)
			(layer "F.SilkS")
		)
		(fp_line
			(start -0.7874 0.4064)
			(end -0.7874 -0.4064)
			(stroke
				(width 0.1524)
				(type default)
			)
			(layer "F.SilkS")
		)
		(fp_line
			(start -0.12065 -0.305054)
			(end -0.12065 -0.2794)
			(stroke
				(width 0.1)
				(type default)
			)
			(layer "F.Fab")
		)
		(fp_line
			(start -0.67945 -0.305054)
			(end -0.12065 -0.305054)
			(stroke
				(width 0.1)
				(type default)
			)
			(layer "F.Fab")
		)
		(fp_line
			(start 0.67945 -0.3048)
			(end 0.67945 0.3048)
			(stroke
				(width 0.1)
				(type default)
			)
			(layer "F.Fab")
		)
		(fp_line
			(start 0.12065 -0.3048)
			(end 0.67945 -0.3048)
			(stroke
				(width 0.1)
				(type default)
			)
			(layer "F.Fab")
		)
		(fp_line
			(start 0.12065 -0.2794)
			(end 0.12065 -0.3048)
			(stroke
				(width 0.1)
				(type default)
			)
			(layer "F.Fab")
		)
		(fp_line
			(start -0.12065 -0.2794)
			(end 0.12065 -0.2794)
			(stroke
				(width 0.1)
				(type default)
			)
			(layer "F.Fab")
		)
		(fp_line
			(start 0.120396 0.2794)
			(end -0.12065 0.2794)
			(stroke
				(width 0.1)
				(type default)
			)
			(layer "F.Fab")
		)
		(fp_line
			(start -0.12065 0.2794)
			(end -0.12065 0.3048)
			(stroke
				(width 0.1)
				(type default)
			)
			(layer "F.Fab")
		)
		(fp_line
			(start 0.67945 0.3048)
			(end 0.120396 0.3048)
			(stroke
				(width 0.1)
				(type default)
			)
			(layer "F.Fab")
		)
		(fp_line
			(start 0.120396 0.3048)
			(end 0.120396 0.2794)
			(stroke
				(width 0.1)
				(type default)
			)
			(layer "F.Fab")
		)
		(fp_line
			(start -0.12065 0.3048)
			(end -0.67945 0.3048)
			(stroke
				(width 0.1)
				(type default)
			)
			(layer "F.Fab")
		)
		(fp_line
			(start -0.67945 0.3048)
			(end -0.67945 -0.305054)
			(stroke
				(width 0.1)
				(type default)
			)
			(layer "F.Fab")
		)
		(pad "1" smd rect
			(at -0.40005 0 270)
			(size 0.4572 0.508)
			(layers "F.Cu" "F.Mask" "F.Paste")
			(net "I3C_SPD_DDRGL_CPU0_SCL")
		)
		(pad "2" smd rect
			(at 0.40005 0 270)
			(size 0.4572 0.508)
			(layers "F.Cu" "F.Mask" "F.Paste")
			(net "I3C_SPD_DDRGL_CPU0_LVC1_SCL")
		)
	)
)
